# BASEBOARD_FAB2 (Tioga Pass) — schematic netlist excerpt (pin names and nets, part order shuffled) for the footprints in the layout excerpt that follows; sources: Cadence DE-HDL packaged netlist, KiCad conversion of Wiwynn_Tioga_Pass_MB.brd

R25W27  120R2F-GP  1%  pkg RCL_GP  page 151 : \1\ = BMC_M_CKE ; \2\ = P1V2_AUX_BMC
C3L8  CAP  10UF 16V 10% X6S  pkg 0805  page 236 : A = VR_FET_SW_P12V_STBY_PVDDQ_DEF ; B = GND
R8F37  RES  0.0 5% EMPTY  pkg 0402  page 93 : A = FM_CPU_ERR0_LVT3_N ; B = FM_CPU_ERR0_PCH_N

(kicad_pcb
	(version 20260206)
	(generator "pcbnew")
	(generator_version "10.0")
	(general
		(thickness 1.6)
		(legacy_teardrops no)
	)
	(paper "A4")
	(title_block
		(title "Wiwynn_Tioga_Pass_MB.brd")
		(comment 1 "Tioga Pass / footprints 3547-3549 of 4770")
	)
	(layers
		(0 "F.Cu" signal "TOP")
		(4 "In1.Cu" signal "L2GND")
		(6 "In2.Cu" signal "L3")
		(8 "In3.Cu" signal "L4GND")
		(10 "In4.Cu" signal "L5")
		(12 "In5.Cu" signal "L6GND")
		(14 "In6.Cu" signal "L7VCC")
		(16 "In7.Cu" signal "L8VCC")
		(18 "In8.Cu" signal "L9GND")
		(20 "In9.Cu" signal "L10")
		(22 "In10.Cu" signal "L11GND")
		(24 "In11.Cu" signal "L12")
		(26 "In12.Cu" signal "L13GND")
		(2 "B.Cu" signal "BOTTOM")
		(9 "F.Adhes" user "F.Adhesive")
		(11 "B.Adhes" user "B.Adhesive")
		(13 "F.Paste" user "Package Geometry/Pastemask Top")
		(15 "B.Paste" user "Package Geometry/Pastemask Bottom")
		(5 "F.SilkS" user "Ref Des/Silkscreen Top")
		(7 "B.SilkS" user "Ref Des/Silkscreen Bottom")
		(1 "F.Mask" user "Board Geometry/Soldermask Top")
		(3 "B.Mask" user "Board Geometry/Soldermask Bottom")
		(17 "Dwgs.User" user "User.Drawings")
		(19 "Cmts.User" user "User.Comments")
		(21 "Eco1.User" user "User.Eco1")
		(23 "Eco2.User" user "User.Eco2")
		(25 "Edge.Cuts" user "Board Geometry/Outline")
		(27 "Margin" user)
		(31 "F.CrtYd" user "Package Geometry/Place Bound Top")
		(29 "B.CrtYd" user "Package Geometry/Place Bound Bottom")
		(35 "F.Fab" user "Ref Des/Assembly Top")
		(33 "B.Fab" user "Ref Des/Assembly Bottom")
	)
	(footprint ""
		(layer "B.Cu")
		(at 379.3998 -154.467306)
		(property "Reference" "C3L8"
			(at 0 0 0)
			(layer "B.SilkS")
			(hide yes)
			(effects
				(font
					(size 1.27 1.27)
				)
				(justify mirror)
			)
		)
		(property "Value" ""
			(at 0 0 0)
			(layer "B.Fab")
			(effects
				(font
					(size 1.27 1.27)
				)
				(justify mirror)
			)
		)
		(duplicate_pad_numbers_are_jumpers no)
		(fp_poly
			(pts
				(xy 0.7239 -0.2159) (xy -0.7239 -0.2159) (xy -0.7239 1.9939) (xy 0.7239 1.9939)
			)
			(stroke
				(width 0)
				(type default)
			)
			(fill no)
			(layer "B.CrtYd")
		)
		(fp_line
			(start -0.7239 -0.2159)
			(end 0.7239 -0.2159)
			(stroke
				(width 0.1)
				(type default)
			)
			(layer "B.Fab")
		)
		(fp_line
			(start -0.7239 1.9939)
			(end -0.7239 -0.2159)
			(stroke
				(width 0.1)
				(type default)
			)
			(layer "B.Fab")
		)
		(fp_line
			(start 0.7239 -0.2159)
			(end 0.7239 1.9939)
			(stroke
				(width 0.1)
				(type default)
			)
			(layer "B.Fab")
		)
		(fp_line
			(start 0.7239 1.9939)
			(end -0.7239 1.9939)
			(stroke
				(width 0.1)
				(type default)
			)
			(layer "B.Fab")
		)
		(pad "1" smd rect
			(at 0 0 180)
			(size 1.27 1.016)
			(layers "B.Cu" "B.Mask" "B.Paste")
			(net "VR_FET_SW_P12V_STBY_PVDDQ_DEF")
		)
		(pad "2" smd rect
			(at 0 1.778 180)
			(size 1.27 1.016)
			(layers "B.Cu" "B.Mask" "B.Paste")
			(net "GND")
		)
		(zone
			(layer "B.Cu")
			(hatch none 0.5)
			(connect_pads
				(clearance 0)
			)
			(min_thickness 0.25)
			(keepout
				(tracks not_allowed)
				(vias allowed)
				(pads allowed)
				(copperpour not_allowed)
				(footprints allowed)
			)
			(placement
				(enabled no)
				(sheetname "")
			)
			(fill
				(thermal_gap 0.5)
				(thermal_bridge_width 0.5)
				(island_removal_mode 0)
			)
			(polygon
				(pts
					(xy 380.0348 -153.959306) (xy 378.7648 -153.959306) (xy 378.7648 -153.197306) (xy 380.0348 -153.197306)
				)
			)
		)
	)
	(footprint ""
		(layer "B.Cu")
		(at 412.313374 -48.687482 -90)
		(property "Reference" "R8F37"
			(at 0 0 90)
			(layer "B.SilkS")
			(hide yes)
			(effects
				(font
					(size 1.27 1.27)
				)
				(justify mirror)
			)
		)
		(property "Value" ""
			(at 0 0 90)
			(layer "B.Fab")
			(effects
				(font
					(size 1.27 1.27)
				)
				(justify mirror)
			)
		)
		(duplicate_pad_numbers_are_jumpers no)
		(fp_poly
			(pts
				(xy 0.2794 -0.1016) (xy -0.2794 -0.1016) (xy -0.2794 0.9906) (xy 0.2794 0.9906)
			)
			(stroke
				(width 0)
				(type default)
			)
			(fill no)
			(layer "B.CrtYd")
		)
		(fp_line
			(start -0.2794 0.9906)
			(end -0.2794 -0.1016)
			(stroke
				(width 0.1)
				(type default)
			)
			(layer "B.Fab")
		)
		(fp_line
			(start 0.2794 0.9906)
			(end -0.2794 0.9906)
			(stroke
				(width 0.1)
				(type default)
			)
			(layer "B.Fab")
		)
		(fp_line
			(start -0.2794 -0.1016)
			(end 0.2794 -0.1016)
			(stroke
				(width 0.1)
				(type default)
			)
			(layer "B.Fab")
		)
		(fp_line
			(start 0.2794 -0.1016)
			(end 0.2794 0.9906)
			(stroke
				(width 0.1)
				(type default)
			)
			(layer "B.Fab")
		)
		(pad "1" smd rect
			(at 0 0 90)
			(size 0.508 0.508)
			(layers "B.Cu" "B.Mask" "B.Paste")
			(net "FM_CPU_ERR0_LVT3_N")
		)
		(pad "2" smd rect
			(at 0 0.889 90)
			(size 0.508 0.508)
			(layers "B.Cu" "B.Mask" "B.Paste")
			(net "FM_CPU_ERR0_PCH_N")
		)
		(zone
			(layer "B.Cu")
			(hatch none 0.5)
			(connect_pads
				(clearance 0)
			)
			(min_thickness 0.25)
			(keepout
				(tracks not_allowed)
				(vias allowed)
				(pads allowed)
				(copperpour not_allowed)
				(footprints allowed)
			)
			(placement
				(enabled no)
				(sheetname "")
			)
			(fill
				(thermal_gap 0.5)
				(thermal_bridge_width 0.5)
				(island_removal_mode 0)
			)
			(polygon
				(pts
					(xy 411.678374 -48.433482) (xy 411.678374 -48.941482) (xy 412.059374 -48.941482) (xy 412.059374 -48.433482)
				)
			)
		)
		(zone
			(layer "B.Cu")
			(hatch none 0.5)
			(connect_pads
				(clearance 0)
			)
			(min_thickness 0.25)
			(keepout
				(tracks allowed)
				(vias not_allowed)
				(pads allowed)
				(copperpour not_allowed)
				(footprints allowed)
			)
			(placement
				(enabled no)
				(sheetname "")
			)
			(fill
				(thermal_gap 0.5)
				(thermal_bridge_width 0.5)
				(island_removal_mode 0)
			)
			(polygon
				(pts
					(xy 412.059374 -48.433482) (xy 412.059374 -48.941482) (xy 411.678374 -48.941482) (xy 411.678374 -48.433482)
				)
			)
		)
	)
	(footprint ""
		(layer "B.Cu")
		(at 448.55638 -32.4485 90)
		(property "Reference" "R25W27"
			(at 0 0 90)
			(layer "B.SilkS")
			(hide yes)
			(effects
				(font
					(size 1.27 1.27)
				)
				(justify mirror)
			)
		)
		(property "Value" "*"
			(at -0.064008 -4.108196 90)
			(unlocked yes)
			(layer "B.Fab")
			(hide yes)
			(effects
				(font
					(size 1.27 1.016)
					(thickness 0.1524)
				)
				(justify mirror)
			)
		)
		(property "Device Type" "120R2F-GP_RCL_GP-120R2F-GP,64.A"
			(at -0.064008 -5.632196 90)
			(unlocked yes)
			(layer "B.Fab")
			(hide yes)
			(effects
				(font
					(size 1.27 1.016)
					(thickness 0.1524)
				)
				(justify mirror)
			)
		)
		(duplicate_pad_numbers_are_jumpers no)
		(fp_line
			(start 0.508 -0.9398)
			(end 0.508 0.9398)
			(stroke
				(width 0.1524)
				(type default)
			)
			(layer "B.SilkS")
		)
		(fp_line
			(start -0.508 -0.9398)
			(end 0.508 -0.9398)
			(stroke
				(width 0.1524)
				(type default)
			)
			(layer "B.SilkS")
		)
		(fp_rect
			(start 0.508 0.9398)
			(end -0.508 -0.9398)
			(stroke
				(width 0)
				(type default)
			)
			(fill no)
			(layer "B.CrtYd")
		)
		(fp_rect
			(start 0.508 0.9398)
			(end -0.508 -0.9398)
			(stroke
				(width 0)
				(type default)
			)
			(fill no)
			(layer "B.Fab")
		)
		(pad "1" smd custom
			(at 0 -0.4445 270)
			(size 0.1397 0.1397)
			(layers "B.Cu" "B.Mask" "B.Paste")
			(net "BMC_M_CKE")
			(options
				(clearance outline)
				(anchor circle)
			)
			(primitives
				(gr_poly
					(pts
						(arc
							(start -0.1778 0.2794)
							(mid -0.249642 0.249642)
							(end -0.2794 0.1778)
						)
						(arc
							(start -0.2794 -0.1778)
							(mid -0.249642 -0.249642)
							(end -0.1778 -0.2794)
						)
						(arc
							(start 0.1778 -0.2794)
							(mid 0.249642 -0.249642)
							(end 0.2794 -0.1778)
						)
						(arc
							(start 0.2794 0.1778)
							(mid 0.249642 0.249642)
							(end 0.1778 0.2794)
						)
					)
					(width 0)
					(fill yes)
				)
			)
		)
		(pad "2" smd custom
			(at 0 0.4445 270)
			(size 0.1397 0.1397)
			(layers "B.Cu" "B.Mask" "B.Paste")
			(net "P1V2_AUX_BMC")
			(options
				(clearance outline)
				(anchor circle)
			)
			(primitives
				(gr_poly
					(pts
						(arc
							(start -0.1778 0.2794)
							(mid -0.249642 0.249642)
							(end -0.2794 0.1778)
						)
						(arc
							(start -0.2794 -0.1778)
							(mid -0.249642 -0.249642)
							(end -0.1778 -0.2794)
						)
						(arc
							(start 0.1778 -0.2794)
							(mid 0.249642 -0.249642)
							(end 0.2794 -0.1778)
						)
						(arc
							(start 0.2794 0.1778)
							(mid 0.249642 0.249642)
							(end 0.1778 0.2794)
						)
					)
					(width 0)
					(fill yes)
				)
			)
		)
	)
)
